# S9S_MB_2U (Grand Teton) — schematic netlist excerpt (pin names and nets, part order shuffled) for the footprints in the layout excerpt that follows; sources: Cadence DE-HDL packaged netlist, KiCad conversion of 03242023_DA0F0TMBIJ0_F0T_Motherboard_J_brd_V01_OCP.brd

PU72_P0_4  ISL99390FRZTR5935  ISL99390FRZ-TR5935 IC  pkg QFN21_6X5XB  page 272
  VOS  = PVCCFA_EHV_FIVRA_CPU0_VOS4
  AGND  = GND
  VCC  = PVCCFA_EHV_FIVRA_CPU0_VDD4
  PVCC  = PVCCFA_EHV_FIVRA_CPU0_PVCC2
  PGND1  = GND
  GL1  = NC
  PGND2  = GND
  SW  = SW_PVCCFA_EHV_FIVRA_CPU0_SW4
  VIN1  = SW_P12V_PVCCFA_EHV_FIVRA_CPU0_L
  VIN2  = SW_P12V_PVCCFA_EHV_FIVRA_CPU0_L
  DNC  = NC
  PHASE  = SW_PVCCFA_EHV_FIVRA_CPU0_BOOTR4
  BOOT  = SW_PVCCFA_EHV_FIVRA_CPU0_BOOT4
  PWM  = PVCCFA_EHV_FIVRA_CPU0_PWM4
  EN  = PVCCFA_EHV_FIVRA_CPU0_VDD4
  TOUT_FLT  = PVCCFA_EHV_FIVRA_CPU0_BTSEN
  LSET  = PVCCFA_EHV_FIVRA_CPU0_LSET4
  IOUT  = PVCCFA_EHV_FIVRA_CPU0_IMON4
  REFIN  = PVCCIN_CPU0_VREF
  PGND3  = GND
  GL2  = NC

(kicad_pcb
	(version 20260206)
	(generator "pcbnew")
	(generator_version "10.0")
	(general
		(thickness 1.6)
		(legacy_teardrops no)
	)
	(paper "A4")
	(title_block
		(title "03242023_DA0F0TMBIJ0_F0T_Motherboard_J_brd_V01_OCP.brd")
		(comment 1 "Grand Teton / footprints 2142-2142 of 6105")
	)
	(layers
		(0 "F.Cu" signal "TOP")
		(4 "In1.Cu" signal "GND")
		(6 "In2.Cu" signal "IN1")
		(8 "In3.Cu" signal "GND1")
		(10 "In4.Cu" signal "IN2")
		(12 "In5.Cu" signal "GND2")
		(14 "In6.Cu" signal "IN3")
		(16 "In7.Cu" signal "GND3")
		(18 "In8.Cu" signal "VCC")
		(20 "In9.Cu" signal "VCC1")
		(22 "In10.Cu" signal "GND4")
		(24 "In11.Cu" signal "IN4")
		(26 "In12.Cu" signal "GND5")
		(28 "In13.Cu" signal "IN5")
		(30 "In14.Cu" signal "GND6")
		(32 "In15.Cu" signal "IN6")
		(34 "In16.Cu" signal "GND7")
		(2 "B.Cu" signal "BOTTOM")
		(9 "F.Adhes" user "F.Adhesive")
		(11 "B.Adhes" user "B.Adhesive")
		(13 "F.Paste" user "Package Geometry/Pastemask Top")
		(15 "B.Paste" user "Package Geometry/Pastemask Bottom")
		(5 "F.SilkS" user "Ref Des/Silkscreen Top")
		(7 "B.SilkS" user "Ref Des/Silkscreen Bottom")
		(1 "F.Mask" user "Board Geometry/Soldermask Top")
		(3 "B.Mask" user "Board Geometry/Soldermask Bottom")
		(17 "Dwgs.User" user "User.Drawings")
		(19 "Cmts.User" user "User.Comments")
		(21 "Eco1.User" user "User.Eco1")
		(23 "Eco2.User" user "User.Eco2")
		(25 "Edge.Cuts" user "Board Geometry/Outline")
		(27 "Margin" user)
		(31 "F.CrtYd" user "Package Geometry/Place Bound Top")
		(29 "B.CrtYd" user "Package Geometry/Place Bound Bottom")
		(35 "F.Fab" user "Ref Des/Assembly Top")
		(33 "B.Fab" user "Ref Des/Assembly Bottom")
	)
	(footprint ""
		(layer "F.Cu")
		(at 288.786062 -362.7755)
		(property "Reference" "PU72_P0_4"
			(at -10.910062 -7.494778 0)
			(unlocked yes)
			(layer "F.SilkS")
			(effects
				(font
					(size 0.7874 0.5842)
					(thickness 0.1524)
				)
				(justify left)
			)
		)
		(property "Value" ""
			(at 0 0 0)
			(layer "F.Fab")
			(effects
				(font
					(size 1.27 1.27)
				)
			)
		)
		(duplicate_pad_numbers_are_jumpers no)
		(fp_line
			(start -2.500122 -2.999994)
			(end -2.24409 -2.999994)
			(stroke
				(width 0.1524)
				(type default)
			)
			(layer "F.SilkS")
		)
		(fp_line
			(start -2.500122 -2.529078)
			(end -2.500122 -2.999994)
			(stroke
				(width 0.1524)
				(type default)
			)
			(layer "F.SilkS")
		)
		(fp_line
			(start -2.500122 0.6604)
			(end -2.500122 0.229108)
			(stroke
				(width 0.1524)
				(type default)
			)
			(layer "F.SilkS")
		)
		(fp_line
			(start -2.500122 2.999994)
			(end -2.500122 2.339594)
			(stroke
				(width 0.1524)
				(type default)
			)
			(layer "F.SilkS")
		)
		(fp_line
			(start -2.2987 2.999994)
			(end -2.500122 2.999994)
			(stroke
				(width 0.1524)
				(type default)
			)
			(layer "F.SilkS")
		)
		(fp_line
			(start 2.31394 -2.999994)
			(end 2.500122 -2.999994)
			(stroke
				(width 0.1524)
				(type default)
			)
			(layer "F.SilkS")
		)
		(fp_line
			(start 2.500122 -2.999994)
			(end 2.500122 -2.44348)
			(stroke
				(width 0.1524)
				(type default)
			)
			(layer "F.SilkS")
		)
		(fp_line
			(start 2.500122 2.339594)
			(end 2.500122 2.999994)
			(stroke
				(width 0.1524)
				(type default)
			)
			(layer "F.SilkS")
		)
		(fp_line
			(start 2.500122 2.999994)
			(end 2.2987 2.999994)
			(stroke
				(width 0.1524)
				(type default)
			)
			(layer "F.SilkS")
		)
		(fp_poly
			(pts
				(xy -2.211832 -3.514598) (xy -2.719832 -2.498598) (xy -3.227832 -3.514598)
			)
			(stroke
				(width 0)
				(type default)
			)
			(fill yes)
			(layer "F.SilkS")
		)
		(fp_line
			(start -2.500122 -2.999994)
			(end 2.500122 -2.999994)
			(stroke
				(width 0.1)
				(type default)
			)
			(layer "F.Fab")
		)
		(fp_line
			(start -2.500122 2.999994)
			(end -2.500122 -2.999994)
			(stroke
				(width 0.1)
				(type default)
			)
			(layer "F.Fab")
		)
		(fp_line
			(start 2.500122 -2.999994)
			(end 2.500122 2.999994)
			(stroke
				(width 0.1)
				(type default)
			)
			(layer "F.Fab")
		)
		(fp_line
			(start 2.500122 2.999994)
			(end -2.500122 2.999994)
			(stroke
				(width 0.1)
				(type default)
			)
			(layer "F.Fab")
		)
		(fp_poly
			(pts
				(xy -4.218432 -2.783078) (xy -4.218432 -1.767078) (xy -3.202432 -2.275078)
			)
			(stroke
				(width 0)
				(type default)
			)
			(fill yes)
			(layer "F.Fab")
		)
		(pad "1" smd rect
			(at -2.400046 -2.275078 90)
			(size 0.2286 0.6096)
			(layers "F.Cu" "F.Mask" "F.Paste")
			(net "PVCCFA_EHV_FIVRA_CPU0_VOS4")
		)
		(pad "2" smd rect
			(at -2.400046 -1.82499 90)
			(size 0.2286 0.6096)
			(layers "F.Cu" "F.Mask" "F.Paste")
			(net "GND")
		)
		(pad "3" smd rect
			(at -2.400046 -1.374902 90)
			(size 0.2286 0.6096)
			(layers "F.Cu" "F.Mask" "F.Paste")
			(net "PVCCFA_EHV_FIVRA_CPU0_VDD4")
		)
		(pad "4" smd rect
			(at -2.400046 -0.925068 90)
			(size 0.2286 0.6096)
			(layers "F.Cu" "F.Mask" "F.Paste")
			(net "PVCCFA_EHV_FIVRA_CPU0_PVCC2")
		)
		(pad "5" smd rect
			(at -2.400046 -0.47498 90)
			(size 0.2286 0.6096)
			(layers "F.Cu" "F.Mask" "F.Paste")
			(net "GND")
		)
		(pad "6" smd rect
			(at -2.400046 -0.024892 90)
			(size 0.2286 0.6096)
			(layers "F.Cu" "F.Mask" "F.Paste")
			(net "Net_8508")
		)
		(pad "7_9-20_24" smd circle
			(at 0 1.150112 90)
			(size 0 0)
			(layers "F.Cu" "F.Mask" "F.Paste")
			(net "GND")
		)
		(pad "10_19" smd rect
			(at 0 2.899918 90)
			(size 0.6096 4.318)
			(layers "F.Cu" "F.Mask" "F.Paste")
			(net "SW_PVCCFA_EHV_FIVRA_CPU0_SW4")
		)
		(pad "25_29" smd rect
			(at 1.549908 -1.279906 270)
			(size 2.0574 2.3114)
			(layers "F.Cu" "F.Mask" "F.Paste")
			(net "SW_P12V_PVCCFA_EHV_FIVRA_CPU0_L")
		)
		(pad "30" smd rect
			(at 2.05994 -2.899918)
			(size 0.2286 0.6096)
			(layers "F.Cu" "F.Mask" "F.Paste")
			(net "SW_P12V_PVCCFA_EHV_FIVRA_CPU0_L")
		)
		(pad "31" smd rect
			(at 1.610106 -2.899918)
			(size 0.2286 0.6096)
			(layers "F.Cu" "F.Mask" "F.Paste")
			(net "Net_8509")
		)
		(pad "32" smd rect
			(at 1.160018 -2.899918)
			(size 0.2286 0.6096)
			(layers "F.Cu" "F.Mask" "F.Paste")
			(net "SW_PVCCFA_EHV_FIVRA_CPU0_BOOTR4")
		)
		(pad "33" smd rect
			(at 0.70993 -2.899918)
			(size 0.2286 0.6096)
			(layers "F.Cu" "F.Mask" "F.Paste")
			(net "SW_PVCCFA_EHV_FIVRA_CPU0_BOOT4")
		)
		(pad "34" smd rect
			(at 0.260096 -2.899918)
			(size 0.2286 0.6096)
			(layers "F.Cu" "F.Mask" "F.Paste")
			(net "PVCCFA_EHV_FIVRA_CPU0_PWM4")
		)
		(pad "35" smd rect
			(at -0.189992 -2.899918)
			(size 0.2286 0.6096)
			(layers "F.Cu" "F.Mask" "F.Paste")
			(net "PVCCFA_EHV_FIVRA_CPU0_VDD4")
		)
		(pad "36" smd rect
			(at -0.64008 -2.899918)
			(size 0.2286 0.6096)
			(layers "F.Cu" "F.Mask" "F.Paste")
			(net "PVCCFA_EHV_FIVRA_CPU0_BTSEN")
		)
		(pad "37" smd rect
			(at -1.089914 -2.899918)
			(size 0.2286 0.6096)
			(layers "F.Cu" "F.Mask" "F.Paste")
			(net "PVCCFA_EHV_FIVRA_CPU0_LSET4")
		)
		(pad "38" smd rect
			(at -1.540002 -2.899918)
			(size 0.2286 0.6096)
			(layers "F.Cu" "F.Mask" "F.Paste")
			(net "PVCCFA_EHV_FIVRA_CPU0_IMON4")
		)
		(pad "39" smd rect
			(at -1.99009 -2.899918)
			(size 0.2286 0.6096)
			(layers "F.Cu" "F.Mask" "F.Paste")
			(net "PVCCIN_CPU0_VREF")
		)
		(pad "40" smd rect
			(at -0.87503 -1.27508)
			(size 1.7526 1.9558)
			(layers "F.Cu" "F.Mask" "F.Paste")
			(net "GND")
		)
		(pad "41" smd rect
			(at -1.525016 0.249936 270)
			(size 0.3048 0.4572)
			(layers "F.Cu" "F.Mask" "F.Paste")
			(net "Net_8507")
		)
		(zone
			(layer "F.Cu")
			(hatch none 0.5)
			(connect_pads
				(clearance 0)
			)
			(min_thickness 0.25)
			(keepout
				(tracks not_allowed)
				(vias allowed)
				(pads allowed)
				(copperpour not_allowed)
				(footprints allowed)
			)
			(placement
				(enabled no)
				(sheetname "")
			)
			(fill
				(thermal_gap 0.5)
				(thermal_bridge_width 0.5)
				(island_removal_mode 0)
			)
			(polygon
				(pts
					(xy 286.28594 -359.775506) (xy 286.28594 -360.500168) (xy 291.286184 -360.500168) (xy 291.286184 -359.775506)
					(xy 290.995862 -359.775506) (xy 290.995862 -360.231182) (xy 286.576262 -360.231182) (xy 286.576262 -359.775506)
				)
			)
		)
		(zone
			(layer "F.Cu")
			(hatch none 0.5)
			(connect_pads
				(clearance 0)
			)
			(min_thickness 0.25)
			(keepout
				(tracks not_allowed)
				(vias allowed)
				(pads allowed)
				(copperpour not_allowed)
				(footprints allowed)
			)
			(placement
				(enabled no)
				(sheetname "")
			)
			(fill
				(thermal_gap 0.5)
				(thermal_bridge_width 0.5)
				(island_removal_mode 0)
			)
			(polygon
				(pts
					(xy 287.0073 -363.02188) (xy 287.78708 -363.02188) (xy 287.78708 -362.712508) (xy 287.83534 -362.712508)
					(xy 287.83534 -362.08716) (xy 287.77438 -362.0262) (xy 286.28594 -362.0262) (xy 286.28594 -362.482892)
					(xy 286.981646 -362.482892) (xy 286.981646 -362.322364) (xy 287.540446 -362.322364) (xy 287.540446 -362.728764)
					(xy 286.981646 -362.728764) (xy 286.981646 -362.508292) (xy 286.28594 -362.508292) (xy 286.28594 -362.635292)
					(xy 286.741616 -362.635292) (xy 286.741616 -363.007148) (xy 287.0073 -363.007148)
				)
			)
		)
	)
)
